FILE_TYPE = CONNECTIVITY;
{Allegro Design Entry HDL 16.6-p007 (v16-6-112F) 10/10/2012}
"PAGE_NUMBER" = 172;
0"NC";
1"GND\g";
2"GND\g";
3"GND\g";
4"P12V\g";
5"GND\g";
6"P5V\g";
7"GND\g";
8"GND\g";
9"P5V_HDD_SATA"VOLTAGE"5";
10"P12V_HDD_SATA"VOLTAGE"12";
11"SATA6G_S1_TX_DN";
12"SATA6G_S1_RX_DP";
13"SATA6G_S1_TX_C_DN";
14"SATA6G_S1_RX_C_DP";
15"SATA6G_S1_RX_DN";
16"SATA6G_S1_TX_DP";
17"SATA6G_S1_TX_C_DP";
18"SATA6G_S1_RX_C_DN";
%"CONN7_E82125014"
"2","(-2000,50)","0","mstr_conn","I17";
;
CDS_LIB"mstr_conn"
ROOM"ST_SATA"
PACK_TYPE"PIP_TH"
CDS_SEC"1"
$SEC"1"
CDS_LOCATION"J8A3"
LOCATION"J8A3"
MATERIAL"EMPTY"
PART_NUMBER"E82125-014";
"MH2"
$PN"MH2"1;
"GND<0>"
$PN"7"1;
"SATA_RXN"
$PN"5"18;
"SATA_RXP"
$PN"6"14;
"GND<1>"
$PN"4"1;
"SATA_TXN"
$PN"3"13;
"SATA_TXP"
$PN"2"17;
"MH1"
$PN"MH1"1;
"GND<2>"
$PN"1"1;
%"GND"
"1","(-1650,-425)","0","mstr_symbols","I2";
;
HDL_POWER"GND"
VOLTAGE"0"
SIZE"1B"
CDS_LIB"mstr_symbols"
BODY_TYPE"PLUMBING"
ROOM"ST_SATA";
"A\NAC"1;
%"CONN4_H73295001"
"1","(0,1900)","0","mstr_conn","I25";
;
CDS_SEC"1"
CDS_LIB"mstr_conn"
PACK_TYPE"PIP"
SEC_TYPE"PIP"
SEC"1"
CDS_LOCATION"J8A4"
ROOM"ST_SATA"
PART_NUMBER"H73295-001"
LOCATION"J8A4"
MATERIAL"EMPTY";
"IO2"
$PN"2"2;
"IO3"
$PN"3"2;
"IO4"
$PN"4"10;
"IO1"
$PN"1"9;
%"GND"
"1","(-300,1550)","0","mstr_symbols","I26";
;
HDL_POWER"GND"
ROOM"ST_SATA"
CDS_LIB"mstr_symbols"
VOLTAGE"0"
SIZE"1B"
BODY_TYPE"PLUMBING";
"A\NAC"2;
%"GND"
"1","(-1125,1300)","0","mstr_symbols","I35";
;
HDL_POWER"GND"
VOLTAGE"0"
CDS_LIB"mstr_symbols"
SIZE"1B"
BODY_TYPE"PLUMBING"
ROOM"ST_SATA";
"A\NAC"3;
%"CAP"
"1","(-1125,1575)","0","mstr_discrete","I36";
;
CDS_SEC"1"
SEC_TYPE"0805"
SEC"1"
CDS_LIB"mstr_discrete"
CDS_LOCATION"C9B2"
ROOM"ST_SATA"
LOCATION"C9B2"
PART_NUMBER"C95333-007"
VALUE"10UF"
TOLERANCE"10%"
PACK_TYPE"0805"
VOLTAGE"16V"
MATERIAL"X6S";
"A"
$PN"1"10;
"B"
$PN"2"3;
%"P12V"
"1","(-2100,2075)","0","mstr_symbols","I37";
;
SIZE"1B"
CDS_LIB"mstr_symbols"
VOLTAGE"12.0V"
BODY_TYPE"PLUMBING"
HDL_POWER"P12V";
"G\NAC"4;
%"FUSE"
"1","(-1825,1800)","0","mstr_discrete","I38";
;
CDS_SEC"1"
CDS_LIB"mstr_discrete"
ROOM"ST_SATA"
PACK_TYPE"SM"
SEC_TYPE"SM"
SEC"1"
CDS_LOCATION"F9B1"
LOCATION"F9B1"
PART_NUMBER"C94311-016"
MATERIAL"IC";
"A<SIZE-1..0>"
$PN"1"4;
"B<SIZE-1..0>"
$PN"2"10;
%"CAP"
"1","(-700,1575)","0","mstr_discrete","I39";
;
CDS_SEC"1"
SEC"1"
SEC_TYPE"0805"
ROOM"ST_SATA"
CDS_LIB"mstr_discrete"
CDS_LOCATION"C9B1"
LOCATION"C9B1"
PART_NUMBER"C95333-007"
VOLTAGE"16V"
VALUE"10UF"
TOLERANCE"10%"
MATERIAL"X6S"
PACK_TYPE"0805";
"A"
$PN"1"9;
"B"
$PN"2"5;
%"GND"
"1","(-700,1300)","0","mstr_symbols","I40";
;
HDL_POWER"GND"
CDS_LIB"mstr_symbols"
VOLTAGE"0"
SIZE"1B"
BODY_TYPE"PLUMBING"
ROOM"ST_SATA";
"A\NAC"5;
%"FUSE"
"1","(-1175,1950)","0","mstr_discrete","I41";
;
CDS_SEC"1"
CDS_LOCATION"F8B1"
ROOM"ST_SATA"
SEC"1"
SEC_TYPE"SMLF"
PACK_TYPE"SMLF"
CDS_LIB"mstr_discrete"
LOCATION"F8B1"
PART_NUMBER"C94311-006"
MATERIAL"IC";
"A<SIZE-1..0>"
$PN"1"6;
"B<SIZE-1..0>"
$PN"2"9;
%"P5V"
"1","(-1425,2275)","0","mstr_symbols","I42";
;
VOLTAGE"+5.0V"
SIZE"1B"
CDS_LIB"mstr_symbols"
BODY_TYPE"PLUMBING"
HDL_POWER"P5V";
"G\NAC"6;
%"CAP_A"
"2","(575,0)","0","dev_discrete","I5";
;
CDS_LOCATION"C2L49"
CDS_SEC"1"
SEC_TYPE"0402V"
SEC"1"
ROOM"ST_SATA"
CDS_LIB"dev_discrete"
LOCATION"C2L49"
PART_NUMBER"A36096-045"
VALUE"0.01UF"
TOLERANCE"10%"
PACK_TYPE"0402V"
VOLTAGE"25V"
MATERIAL"X7R";
"A"
$PN"1"14;
"B"
$PN"2"12;
%"GND"
"1","(-1675,-1550)","0","mstr_symbols","I51";
;
HDL_POWER"GND"
ROOM"ST_SATA"
VOLTAGE"0"
CDS_LIB"mstr_symbols"
SIZE"1B"
BODY_TYPE"PLUMBING";
"A\NAC"7;
%"CONN7_E82125014"
"2","(-2025,-1075)","0","mstr_conn","I52";
;
CDS_LIB"mstr_conn"
PACK_TYPE"PIP_TH"
CDS_SEC"1"
$SEC"1"
CDS_LOCATION"J2M1"
ROOM"ST_SATA"
PART_NUMBER"E82125-014"
LOCATION"J2M1"
MATERIAL"CONN";
"MH2"
$PN"MH2"7;
"GND<0>"
$PN"7"7;
"SATA_RXN"
$PN"5"18;
"SATA_RXP"
$PN"6"14;
"GND<1>"
$PN"4"7;
"SATA_TXN"
$PN"3"13;
"SATA_TXP"
$PN"2"17;
"MH1"
$PN"MH1"7;
"GND<2>"
$PN"1"7;
%"CONN4_H73295001"
"1","(25,925)","0","mstr_conn","I53";
;
CDS_SEC"1"
CDS_LIB"mstr_conn"
PACK_TYPE"PIP"
SEC_TYPE"PIP"
SEC"1"
CDS_LOCATION"J2L1"
ROOM"ST_SATA"
PART_NUMBER"H73295-001"
LOCATION"J2L1"
MATERIAL"CONN";
"IO2"
$PN"2"8;
"IO3"
$PN"3"8;
"IO4"
$PN"4"10;
"IO1"
$PN"1"9;
%"GND"
"1","(-325,575)","0","mstr_symbols","I54";
;
SIZE"1B"
HDL_POWER"GND"
ROOM"ST_SATA"
BODY_TYPE"PLUMBING"
CDS_LIB"mstr_symbols"
VOLTAGE"0";
"A\NAC"8;
%"CAP_A"
"2","(-650,150)","0","dev_discrete","I6";
;
ROOM"ST_SATA"
SEC"1"
SEC_TYPE"0402V"
CDS_SEC"1"
CDS_LOCATION"C2L52"
CDS_LIB"dev_discrete"
PART_NUMBER"A36096-045"
LOCATION"C2L52"
VOLTAGE"25V"
VALUE"0.01UF"
TOLERANCE"10%"
MATERIAL"X7R"
PACK_TYPE"0402V";
"A"
$PN"1"17;
"B"
$PN"2"16;
%"CAP_A"
"2","(-300,-50)","0","dev_discrete","I7";
;
CDS_LOCATION"C2L50"
CDS_SEC"1"
SEC_TYPE"0402V"
SEC"1"
ROOM"ST_SATA"
CDS_LIB"dev_discrete"
LOCATION"C2L50"
PART_NUMBER"A36096-045"
PACK_TYPE"0402V"
VOLTAGE"25V"
MATERIAL"X7R"
TOLERANCE"10%"
VALUE"0.01UF";
"A"
$PN"1"18;
"B"
$PN"2"15;
%"CAP_A"
"2","(100,100)","0","dev_discrete","I8";
;
CDS_LOCATION"C2L51"
ROOM"ST_SATA"
SEC"1"
SEC_TYPE"0402V"
CDS_SEC"1"
CDS_LIB"dev_discrete"
LOCATION"C2L51"
VOLTAGE"25V"
TOLERANCE"10%"
PACK_TYPE"0402V"
MATERIAL"X7R"
PART_NUMBER"A36096-045"
VALUE"0.01UF";
"A"
$PN"1"13;
"B"
$PN"2"11;
END.
